FILE_TYPE = MACRO_DRAWING;
SET COLOR_WIRE YELLOW;
SET COLOR_PROP ORANGE;
SET COLOR_DOT WHITE;
SET COLOR_ARC YELLOW;
SET COLOR_BODY GREEN;
SET COLOR_NOTE PURPLE;
SET PROP_DISPLAY VALUE;
SET PAGE_NUMBER P225;
FORCEADD Q_RES..2
(1700 1025);
FORCEPROP 1 LAST PART_NUMBER CS24702JB10
J 0
(1740 850);
DISPLAY 0.638298 (1740 850);
DISPLAY INVISIBLE (1740 850);
FORCEPROP 1 LAST TOLERANCE 5%
J 0
(1745 1050);
DISPLAY 0.638298 (1745 1050);
FORCEPROP 1 LAST VALUE 4.7K
J 0
(1745 1100);
DISPLAY 0.638298 (1745 1100);
FORCEPROP 1 LAST WATTAGE 1/16W
J 0
(1740 1000);
DISPLAY 0.638298 (1740 1000);
FORCEPROP 1 LAST MATERIAL CHIP
J 0
(1740 950);
DISPLAY 0.638298 (1740 950);
FORCEPROP 1 LAST PACK_TYPE 0402LF
J 0
(1740 900);
DISPLAY 0.638298 (1740 900);
FORCEPROP 1 LAST $LOCATION R4498
J 0
(1745 1150);
DISPLAY 0.638298 (1745 1150);
FORCEPROP 1 LASTPIN (1700 1125) $PN 1
J 0
(1705 1087);
DISPLAY 0.787234 (1705 1087);
FORCEPROP 1 LASTPIN (1700 925) $PN 2
J 0
(1705 935);
DISPLAY 0.787234 (1705 935);
FORCEPROP 1 LAST PATH I11
J 0
(1750 1200);
DISPLAY 0.978723 (1750 1200);
PAINT WHITE (1750 1200);
DISPLAY INVISIBLE (1750 1200);
FORCEPROP 2 LAST CDS_LIB pure_quanta
J 0
(1700 1025);
PAINT MONO (1700 1025);
DISPLAY INVISIBLE (1700 1025);
FORCEPROP 2 LAST CDS_LOCATION R4498
J 0
(1750 1250);
DISPLAY 1.021277 (1750 1250);
DISPLAY INVISIBLE (1750 1250);
FORCEPROP 2 LAST $SEC 1
J 0
(1750 1250);
DISPLAY 0.680851 (1750 1250);
PAINT MONO (1750 1250);
DISPLAY INVISIBLE (1750 1250);
FORCEPROP 2 LAST CDS_SEC 1
J 0
(1750 1250);
DISPLAY 1.021277 (1750 1250);
DISPLAY INVISIBLE (1750 1250);
FORCEADD Q_RES..2
(1950 1025);
FORCEPROP 1 LAST PART_NUMBER CS24702JB10
J 0
(1990 850);
DISPLAY 0.638298 (1990 850);
DISPLAY INVISIBLE (1990 850);
FORCEPROP 1 LAST VALUE 4.7K
J 0
(1995 1100);
DISPLAY 0.638298 (1995 1100);
FORCEPROP 1 LAST PACK_TYPE 0402LF
J 0
(1975 900);
DISPLAY 0.638298 (1975 900);
FORCEPROP 1 LAST TOLERANCE 5%
J 0
(1995 1050);
DISPLAY 0.638298 (1995 1050);
FORCEPROP 1 LAST WATTAGE 1/16W
J 0
(1990 1000);
DISPLAY 0.638298 (1990 1000);
FORCEPROP 1 LAST MATERIAL CHIP
J 0
(1990 950);
DISPLAY 0.638298 (1990 950);
FORCEPROP 1 LAST $LOCATION R4499
J 0
(1995 1150);
DISPLAY 0.638298 (1995 1150);
FORCEPROP 1 LASTPIN (1950 1125) $PN 1
J 0
(1955 1087);
DISPLAY 0.787234 (1955 1087);
FORCEPROP 1 LASTPIN (1950 925) $PN 2
J 0
(1955 935);
DISPLAY 0.787234 (1955 935);
FORCEPROP 1 LAST PATH I12
J 0
(2000 1200);
DISPLAY 0.978723 (2000 1200);
PAINT WHITE (2000 1200);
DISPLAY INVISIBLE (2000 1200);
FORCEPROP 2 LAST CDS_LIB pure_quanta
J 0
(1950 1025);
PAINT MONO (1950 1025);
DISPLAY INVISIBLE (1950 1025);
FORCEPROP 2 LAST CDS_LOCATION R4499
J 0
(2000 1250);
DISPLAY 1.021277 (2000 1250);
DISPLAY INVISIBLE (2000 1250);
FORCEPROP 2 LAST $SEC 1
J 0
(2000 1250);
DISPLAY 0.680851 (2000 1250);
PAINT MONO (2000 1250);
DISPLAY INVISIBLE (2000 1250);
FORCEPROP 2 LAST CDS_SEC 1
J 0
(2000 1250);
DISPLAY 1.021277 (2000 1250);
DISPLAY INVISIBLE (2000 1250);
FORCEADD UNIVERSAL_POWER..1
(1425 1325);
FORCEPROP 3 LASTPIN (1425 1275) SIG_NAME P3V3\g
J 0
(1435 1285);
DISPLAY 0.659574 (1435 1285);
PAINT MONO (1435 1285);
DISPLAY INVISIBLE (1435 1285);
FORCEPROP 1 LAST HDL_POWER P3V3
J 1
(1425 1375);
DISPLAY 0.872340 (1425 1375);
PAINT GREEN (1425 1375);
FORCEPROP 1 LAST PATH I13
J 0
(1475 1350);
DISPLAY 0.872340 (1475 1350);
PAINT AQUA (1475 1350);
DISPLAY INVISIBLE (1475 1350);
FORCEPROP 2 LAST CDS_LIB logical_power
J 0
(1425 1325);
PAINT MONO (1425 1325);
DISPLAY INVISIBLE (1425 1325);
FORCEADD PCA9617ADP..1
(-25 625);
FORCEPROP 1 LAST PART_NUMBER AL009617K02
J 0
(-299 985);
DISPLAY 0.723404 (-299 985);
PAINT GREEN (-299 985);
DISPLAY INVISIBLE (-299 985);
FORCEPROP 2 LAST PART_TYPE SMLF
J 0
(-275 1125);
DISPLAY 1.021277 (-275 1125);
FORCEPROP 1 LAST MATERIAL IC
J 0
(-299 930);
DISPLAY 0.723404 (-299 930);
PAINT GREEN (-299 930);
FORCEPROP 2 LAST VALUE PCA9617ADP
J 0
(-275 1075);
DISPLAY 1.021277 (-275 1075);
FORCEPROP 1 LAST $LOCATION U315
J 0
(-299 1035);
DISPLAY 0.723404 (-299 1035);
PAINT GREEN (-299 1035);
FORCEPROP 0 LASTPIN (400 425) $PN 5
J 0
(410 435);
DISPLAY 0.680851 (410 435);
PAINT MONO (410 435);
FORCEPROP 0 LASTPIN (-450 425) $PN 4
J 2
(-460 435);
DISPLAY 0.680851 (-460 435);
PAINT MONO (-460 435);
FORCEPROP 0 LASTPIN (-450 675) $PN 2
J 2
(-460 685);
DISPLAY 0.680851 (-460 685);
PAINT MONO (-460 685);
FORCEPROP 0 LASTPIN (400 675) $PN 7
J 0
(410 685);
DISPLAY 0.680851 (410 685);
PAINT MONO (410 685);
FORCEPROP 0 LASTPIN (-450 575) $PN 3
J 2
(-460 585);
DISPLAY 0.680851 (-460 585);
PAINT MONO (-460 585);
FORCEPROP 0 LASTPIN (400 575) $PN 6
J 0
(410 585);
DISPLAY 0.680851 (410 585);
PAINT MONO (410 585);
FORCEPROP 0 LASTPIN (-450 825) $PN 1
J 2
(-460 835);
DISPLAY 0.680851 (-460 835);
PAINT MONO (-460 835);
FORCEPROP 0 LASTPIN (400 825) $PN 8
J 0
(410 835);
DISPLAY 0.680851 (410 835);
PAINT MONO (410 835);
FORCEPROP 1 LAST PATH I17
J 0
(-25 625);
DISPLAY 0.723404 (-25 625);
PAINT GREEN (-25 625);
DISPLAY INVISIBLE (-25 625);
FORCEPROP 2 LAST CDS_LIB pure_quanta
J 0
(-25 625);
DISPLAY INVISIBLE (-25 625);
FORCEPROP 1 LAST CDS_LMAN_SYM_OUTLINE -275,300,275,-300
J 0
(-25 625);
DISPLAY 0.468085 (-25 625);
PAINT GREEN (-25 625);
DISPLAY INVISIBLE (-25 625);
FORCEPROP 1 LAST NEEDS_NO_SIZE TRUE
J 0
(250 325);
DISPLAY 0.468085 (250 325);
PAINT GREEN (250 325);
DISPLAY INVISIBLE (250 325);
FORCEPROP 0 LAST CDS_LOCATION U315
J 0
(-275 1175);
DISPLAY 1.021277 (-275 1175);
DISPLAY INVISIBLE (-275 1175);
FORCEPROP 0 LAST $SEC 1
J 0
(-275 1175);
DISPLAY 0.680851 (-275 1175);
PAINT MONO (-275 1175);
DISPLAY INVISIBLE (-275 1175);
FORCEPROP 0 LAST CDS_SEC 1
J 0
(-275 1175);
DISPLAY 1.021277 (-275 1175);
DISPLAY INVISIBLE (-275 1175);
FORCEADD OFFPAGE..6
(-2025 575);
FORCEPROP 2 LAST $XR0 241 
J 0
(-2335 575);
DISPLAY 0.638298 (-2335 575);
PAINT MONO (-2335 575);
FORCEPROP 1 LAST OFFPAGE TRUE
J 0
(-1700 450);
DISPLAY 0.872340 (-1700 450);
DISPLAY INVISIBLE (-1700 450);
FORCEPROP 1 LAST COMMENT_BODY TRUE
J 0
(-1925 500);
DISPLAY 0.872340 (-1925 500);
PAINT GREEN (-1925 500);
DISPLAY INVISIBLE (-1925 500);
FORCEPROP 2 LAST PATH I18
J 0
(-2300 625);
DISPLAY 1.021277 (-2300 625);
DISPLAY INVISIBLE (-2300 625);
FORCEPROP 2 LAST CDS_LIB standard
J 0
(-2025 575);
DISPLAY INVISIBLE (-2025 575);
FORCEADD OFFPAGE..1
(-2025 675);
FORCEPROP 2 LAST $XR0 241 
J 0
(-2277 675);
DISPLAY 0.638298 (-2277 675);
PAINT MONO (-2277 675);
FORCEPROP 1 LAST COMMENT_BODY TRUE
J 0
(-1900 575);
DISPLAY 0.872340 (-1900 575);
PAINT GREEN (-1900 575);
DISPLAY INVISIBLE (-1900 575);
FORCEPROP 1 LAST OFFPAGE TRUE
J 0
(-1700 550);
DISPLAY 0.872340 (-1700 550);
PAINT GREEN (-1700 550);
DISPLAY INVISIBLE (-1700 550);
FORCEPROP 2 LAST PATH I19
J 0
(-2275 725);
DISPLAY 1.021277 (-2275 725);
DISPLAY INVISIBLE (-2275 725);
FORCEPROP 2 LAST CDS_LIB standard
J 0
(-2025 675);
DISPLAY INVISIBLE (-2025 675);
FORCEADD OFFPAGE..3
(3200 -1575);
FORCEPROP 2 LAST $XR0 211 
J 0
(3414 -1575);
DISPLAY 0.638298 (3414 -1575);
PAINT MONO (3414 -1575);
FORCEPROP 1 LAST COMMENT_BODY TRUE
J 0
(3150 -1675);
DISPLAY 0.872340 (3150 -1675);
PAINT GREEN (3150 -1675);
DISPLAY INVISIBLE (3150 -1675);
FORCEPROP 1 LAST OFFPAGE TRUE
J 0
(3525 -1700);
DISPLAY 0.872340 (3525 -1700);
PAINT GREEN (3525 -1700);
DISPLAY INVISIBLE (3525 -1700);
FORCEPROP 2 LAST CDS_LIB standard
J 0
(3200 -1575);
PAINT MONO (3200 -1575);
DISPLAY INVISIBLE (3200 -1575);
FORCEPROP 2 LAST PATH I22
J 0
(3425 -1525);
DISPLAY 1.021277 (3425 -1525);
DISPLAY INVISIBLE (3425 -1525);
FORCEADD OFFPAGE..2
(3200 -1525);
FORCEPROP 2 LAST $XR0 211 
J 0
(3389 -1525);
DISPLAY 0.638298 (3389 -1525);
PAINT MONO (3389 -1525);
FORCEPROP 1 LAST OFFPAGE TRUE
J 0
(3525 -1650);
DISPLAY 0.872340 (3525 -1650);
PAINT GREEN (3525 -1650);
DISPLAY INVISIBLE (3525 -1650);
FORCEPROP 1 LAST COMMENT_BODY TRUE
J 0
(3155 -1620);
DISPLAY 0.872340 (3155 -1620);
PAINT GREEN (3155 -1620);
DISPLAY INVISIBLE (3155 -1620);
FORCEPROP 2 LAST CDS_LIB standard
J 0
(3200 -1525);
PAINT MONO (3200 -1525);
DISPLAY INVISIBLE (3200 -1525);
FORCEPROP 2 LAST PATH I23
J 0
(3400 -1475);
DISPLAY 1.021277 (3400 -1475);
DISPLAY INVISIBLE (3400 -1475);
FORCEADD Q_RES..1
(1525 -1525);
FORCEPROP 1 LAST PART_NUMBER CS03322FB03
J 0
(1475 -1475);
DISPLAY 0.404255 (1475 -1475);
DISPLAY INVISIBLE (1475 -1475);
FORCEPROP 1 LAST MATERIAL CHIP
J 0
(1825 -1525);
DISPLAY 0.510638 (1825 -1525);
FORCEPROP 1 LAST VALUE 33.2
J 2
(1725 -1525);
DISPLAY 0.510638 (1725 -1525);
FORCEPROP 1 LAST TOLERANCE 1%
J 0
(1750 -1525);
DISPLAY 0.510638 (1750 -1525);
FORCEPROP 1 LAST $LOCATION R4480
J 0
(1250 -1525);
DISPLAY 0.808511 (1250 -1525);
FORCEPROP 1 LASTPIN (1425 -1525) $PN 1
J 0
(1437 -1513);
DISPLAY 0.787234 (1437 -1513);
FORCEPROP 1 LASTPIN (1625 -1525) $PN 2
J 0
(1587 -1513);
DISPLAY 0.787234 (1587 -1513);
FORCEPROP 1 LAST PACK_TYPE 0402LF
J 0
(1775 -1525);
DISPLAY 0.510638 (1775 -1525);
DISPLAY INVISIBLE (1775 -1525);
FORCEPROP 1 LAST WATTAGE 1/16W
J 2
(1700 -1450);
DISPLAY 0.404255 (1700 -1450);
DISPLAY INVISIBLE (1700 -1450);
FORCEPROP 2 LAST CDS_LIB pure_quanta
J 0
(1525 -1525);
PAINT MONO (1525 -1525);
DISPLAY INVISIBLE (1525 -1525);
FORCEPROP 1 LAST PATH I24
J 0
(1475 -1375);
DISPLAY 0.978723 (1475 -1375);
PAINT WHITE (1475 -1375);
DISPLAY INVISIBLE (1475 -1375);
FORCEPROP 2 LAST CDS_LOCATION R4480
J 0
(1475 -1325);
DISPLAY 1.021277 (1475 -1325);
DISPLAY INVISIBLE (1475 -1325);
FORCEPROP 2 LAST $SEC 1
J 0
(1475 -1325);
DISPLAY 0.680851 (1475 -1325);
PAINT MONO (1475 -1325);
DISPLAY INVISIBLE (1475 -1325);
FORCEPROP 2 LAST CDS_SEC 1
J 0
(1475 -1325);
DISPLAY 1.021277 (1475 -1325);
DISPLAY INVISIBLE (1475 -1325);
FORCEADD Q_RES..1
(1525 -1575);
FORCEPROP 1 LAST PART_NUMBER CS03322FB03
J 0
(1400 -1450);
DISPLAY 0.510638 (1400 -1450);
DISPLAY INVISIBLE (1400 -1450);
FORCEPROP 1 LAST PACK_TYPE 0402LF
J 0
(1400 -1400);
DISPLAY 0.510638 (1400 -1400);
FORCEPROP 1 LAST MATERIAL CHIP
J 0
(1825 -1575);
DISPLAY 0.510638 (1825 -1575);
FORCEPROP 1 LAST WATTAGE 1/16W
J 2
(1700 -1400);
DISPLAY 0.510638 (1700 -1400);
FORCEPROP 1 LAST VALUE 33.2
J 2
(1725 -1575);
DISPLAY 0.510638 (1725 -1575);
FORCEPROP 1 LAST TOLERANCE 1%
J 0
(1750 -1575);
DISPLAY 0.510638 (1750 -1575);
FORCEPROP 1 LAST $LOCATION R4481
J 0
(1250 -1575);
DISPLAY 0.808511 (1250 -1575);
FORCEPROP 1 LASTPIN (1425 -1575) $PN 1
J 0
(1437 -1563);
DISPLAY 0.787234 (1437 -1563);
FORCEPROP 1 LASTPIN (1625 -1575) $PN 2
J 0
(1587 -1563);
DISPLAY 0.787234 (1587 -1563);
FORCEPROP 2 LAST CDS_LIB pure_quanta
J 0
(1525 -1575);
PAINT MONO (1525 -1575);
DISPLAY INVISIBLE (1525 -1575);
FORCEPROP 1 LAST PATH I25
J 0
(1475 -1425);
DISPLAY 0.978723 (1475 -1425);
PAINT WHITE (1475 -1425);
DISPLAY INVISIBLE (1475 -1425);
FORCEPROP 2 LAST CDS_LOCATION R4481
J 0
(1475 -1375);
DISPLAY 1.021277 (1475 -1375);
DISPLAY INVISIBLE (1475 -1375);
FORCEPROP 2 LAST $SEC 1
J 0
(1475 -1375);
DISPLAY 0.680851 (1475 -1375);
PAINT MONO (1475 -1375);
DISPLAY INVISIBLE (1475 -1375);
FORCEPROP 2 LAST CDS_SEC 1
J 0
(1475 -1375);
DISPLAY 1.021277 (1475 -1375);
DISPLAY INVISIBLE (1475 -1375);
FORCEADD Q_RES..1
(1550 -1025);
FORCEPROP 1 LAST PART_NUMBER CS03322FB03
J 0
(1425 -900);
DISPLAY 0.510638 (1425 -900);
DISPLAY INVISIBLE (1425 -900);
FORCEPROP 1 LAST TOLERANCE 1%
J 0
(1775 -1025);
DISPLAY 0.510638 (1775 -1025);
FORCEPROP 1 LAST VALUE 33.2
J 2
(1750 -1025);
DISPLAY 0.510638 (1750 -1025);
FORCEPROP 1 LAST MATERIAL CHIP
J 0
(1850 -1025);
DISPLAY 0.510638 (1850 -1025);
FORCEPROP 1 LAST WATTAGE 1/16W
J 2
(1725 -850);
DISPLAY 0.510638 (1725 -850);
FORCEPROP 1 LAST PACK_TYPE 0402LF
J 0
(1425 -850);
DISPLAY 0.510638 (1425 -850);
FORCEPROP 1 LAST $LOCATION R4497
J 0
(1275 -1025);
DISPLAY 0.808511 (1275 -1025);
FORCEPROP 1 LASTPIN (1450 -1025) $PN 1
J 0
(1462 -1013);
DISPLAY 0.787234 (1462 -1013);
FORCEPROP 1 LASTPIN (1650 -1025) $PN 2
J 0
(1612 -1013);
DISPLAY 0.787234 (1612 -1013);
FORCEPROP 2 LAST CDS_LIB pure_quanta
J 0
(1550 -1025);
PAINT MONO (1550 -1025);
DISPLAY INVISIBLE (1550 -1025);
FORCEPROP 1 LAST PATH I26
J 0
(1500 -875);
DISPLAY 0.978723 (1500 -875);
PAINT WHITE (1500 -875);
DISPLAY INVISIBLE (1500 -875);
FORCEPROP 2 LAST CDS_LOCATION R4497
J 0
(1500 -825);
DISPLAY 1.021277 (1500 -825);
DISPLAY INVISIBLE (1500 -825);
FORCEPROP 2 LAST $SEC 1
J 0
(1500 -825);
DISPLAY 0.680851 (1500 -825);
PAINT MONO (1500 -825);
DISPLAY INVISIBLE (1500 -825);
FORCEPROP 2 LAST CDS_SEC 1
J 0
(1500 -825);
DISPLAY 1.021277 (1500 -825);
DISPLAY INVISIBLE (1500 -825);
FORCEADD Q_RES..1
(1550 -975);
FORCEPROP 1 LAST PART_NUMBER CS03322FB03
J 0
(1500 -925);
DISPLAY 0.404255 (1500 -925);
DISPLAY INVISIBLE (1500 -925);
FORCEPROP 1 LAST TOLERANCE 1%
J 0
(1775 -975);
DISPLAY 0.510638 (1775 -975);
FORCEPROP 1 LAST VALUE 33.2
J 2
(1750 -975);
DISPLAY 0.510638 (1750 -975);
FORCEPROP 1 LAST MATERIAL CHIP
J 0
(1850 -975);
DISPLAY 0.510638 (1850 -975);
FORCEPROP 1 LAST $LOCATION R4496
J 0
(1275 -975);
DISPLAY 0.808511 (1275 -975);
FORCEPROP 1 LASTPIN (1450 -975) $PN 1
J 0
(1462 -963);
DISPLAY 0.787234 (1462 -963);
FORCEPROP 1 LASTPIN (1650 -975) $PN 2
J 0
(1612 -963);
DISPLAY 0.787234 (1612 -963);
FORCEPROP 2 LAST CDS_LIB pure_quanta
J 0
(1550 -975);
PAINT MONO (1550 -975);
DISPLAY INVISIBLE (1550 -975);
FORCEPROP 1 LAST PATH I27
J 0
(1500 -825);
DISPLAY 0.978723 (1500 -825);
PAINT WHITE (1500 -825);
DISPLAY INVISIBLE (1500 -825);
FORCEPROP 1 LAST WATTAGE 1/16W
J 2
(1725 -900);
DISPLAY 0.404255 (1725 -900);
DISPLAY INVISIBLE (1725 -900);
FORCEPROP 1 LAST PACK_TYPE 0402LF
J 0
(1800 -975);
DISPLAY 0.510638 (1800 -975);
DISPLAY INVISIBLE (1800 -975);
FORCEPROP 2 LAST CDS_LOCATION R4496
J 0
(1500 -775);
DISPLAY 1.021277 (1500 -775);
DISPLAY INVISIBLE (1500 -775);
FORCEPROP 2 LAST $SEC 1
J 0
(1500 -775);
DISPLAY 0.680851 (1500 -775);
PAINT MONO (1500 -775);
DISPLAY INVISIBLE (1500 -775);
FORCEPROP 2 LAST CDS_SEC 1
J 0
(1500 -775);
DISPLAY 1.021277 (1500 -775);
DISPLAY INVISIBLE (1500 -775);
FORCEADD OFFPAGE..3
(3225 -1025);
FORCEPROP 2 LAST $XR0 206 
J 0
(3439 -1025);
DISPLAY 0.638298 (3439 -1025);
PAINT MONO (3439 -1025);
FORCEPROP 2 LAST PATH I28
J 0
(3450 -975);
DISPLAY 1.021277 (3450 -975);
DISPLAY INVISIBLE (3450 -975);
FORCEPROP 1 LAST COMMENT_BODY TRUE
J 0
(3175 -1125);
DISPLAY 0.872340 (3175 -1125);
PAINT GREEN (3175 -1125);
DISPLAY INVISIBLE (3175 -1125);
FORCEPROP 1 LAST OFFPAGE TRUE
J 0
(3550 -1150);
DISPLAY 0.872340 (3550 -1150);
PAINT GREEN (3550 -1150);
DISPLAY INVISIBLE (3550 -1150);
FORCEPROP 2 LAST CDS_LIB standard
J 0
(3225 -1025);
PAINT MONO (3225 -1025);
DISPLAY INVISIBLE (3225 -1025);
FORCEADD OFFPAGE..2
(3225 -975);
FORCEPROP 2 LAST $XR0 206 
J 0
(3414 -975);
DISPLAY 0.638298 (3414 -975);
PAINT MONO (3414 -975);
FORCEPROP 2 LAST PATH I29
J 0
(3425 -925);
DISPLAY 1.021277 (3425 -925);
DISPLAY INVISIBLE (3425 -925);
FORCEPROP 1 LAST OFFPAGE TRUE
J 0
(3550 -1100);
DISPLAY 0.872340 (3550 -1100);
PAINT GREEN (3550 -1100);
DISPLAY INVISIBLE (3550 -1100);
FORCEPROP 1 LAST COMMENT_BODY TRUE
J 0
(3180 -1070);
DISPLAY 0.872340 (3180 -1070);
PAINT GREEN (3180 -1070);
DISPLAY INVISIBLE (3180 -1070);
FORCEPROP 2 LAST CDS_LIB standard
J 0
(3225 -975);
PAINT MONO (3225 -975);
DISPLAY INVISIBLE (3225 -975);
FORCEADD UNIVERSAL_GND..1
(-550 200);
FORCEPROP 3 LASTPIN (-550 250) SIG_NAME GND\g
J 0
(-540 260);
DISPLAY 0.659574 (-540 260);
PAINT MONO (-540 260);
DISPLAY INVISIBLE (-540 260);
FORCEPROP 1 LAST PATH I3
J 0
(-475 200);
DISPLAY 0.872340 (-475 200);
PAINT AQUA (-475 200);
DISPLAY INVISIBLE (-475 200);
FORCEPROP 1 LAST HDL_POWER GND
J 1
(-525 125);
DISPLAY 0.872340 (-525 125);
PAINT GREEN (-525 125);
DISPLAY INVISIBLE (-525 125);
FORCEPROP 2 LAST CDS_LIB logical_power
J 0
(-550 200);
DISPLAY INVISIBLE (-550 200);
FORCEADD OFFPAGE..6
(-1300 -1025);
FORCEPROP 2 LAST $XR0 237 
J 0
(-1580 -1025);
DISPLAY 0.638298 (-1580 -1025);
PAINT MONO (-1580 -1025);
FORCEPROP 2 LAST CDS_LIB standard
J 0
(-1300 -1025);
DISPLAY INVISIBLE (-1300 -1025);
FORCEPROP 2 LAST PATH I30
J 0
(-1250 -950);
DISPLAY 1.021277 (-1250 -950);
DISPLAY INVISIBLE (-1250 -950);
FORCEPROP 1 LAST OFFPAGE TRUE
J 0
(-975 -1150);
DISPLAY 0.872340 (-975 -1150);
DISPLAY INVISIBLE (-975 -1150);
FORCEPROP 1 LAST COMMENT_BODY TRUE
J 0
(-1200 -1100);
DISPLAY 0.872340 (-1200 -1100);
PAINT GREEN (-1200 -1100);
DISPLAY INVISIBLE (-1200 -1100);
FORCEADD OFFPAGE..1
(-1300 -975);
FORCEPROP 2 LAST $XR0 237 
J 0
(-1552 -975);
DISPLAY 0.638298 (-1552 -975);
PAINT MONO (-1552 -975);
FORCEPROP 2 LAST CDS_LIB standard
J 0
(-1300 -975);
DISPLAY INVISIBLE (-1300 -975);
FORCEPROP 2 LAST PATH I31
J 0
(-1250 -900);
DISPLAY 1.021277 (-1250 -900);
DISPLAY INVISIBLE (-1250 -900);
FORCEPROP 1 LAST COMMENT_BODY TRUE
J 0
(-1175 -1075);
DISPLAY 0.872340 (-1175 -1075);
PAINT GREEN (-1175 -1075);
DISPLAY INVISIBLE (-1175 -1075);
FORCEPROP 1 LAST OFFPAGE TRUE
J 0
(-975 -1100);
DISPLAY 0.872340 (-975 -1100);
PAINT GREEN (-975 -1100);
DISPLAY INVISIBLE (-975 -1100);
FORCEADD Q_RES..2
(1425 1050);
FORCEPROP 1 LAST PART_NUMBER CS31002FB08
J 0
(1465 925);
DISPLAY 0.404255 (1465 925);
DISPLAY INVISIBLE (1465 925);
FORCEPROP 1 LAST WATTAGE 1/16W
J 0
(1465 1025);
DISPLAY 0.404255 (1465 1025);
FORCEPROP 1 LAST TOLERANCE 1%
J 0
(1470 1075);
DISPLAY 0.404255 (1470 1075);
FORCEPROP 1 LAST VALUE 10K
J 0
(1470 1125);
DISPLAY 0.404255 (1470 1125);
FORCEPROP 1 LAST MATERIAL EMPTY
J 0
(1465 975);
DISPLAY 0.404255 (1465 975);
FORCEPROP 1 LAST PACK_TYPE 0402LF
J 0
(1465 875);
DISPLAY 0.404255 (1465 875);
FORCEPROP 1 LAST $LOCATION R4500
J 0
(1470 1175);
DISPLAY 0.638298 (1470 1175);
FORCEPROP 1 LASTPIN (1425 1150) $PN 1
J 0
(1430 1112);
DISPLAY 0.787234 (1430 1112);
PAINT MONO (1430 1112);
FORCEPROP 1 LASTPIN (1425 950) $PN 2
J 0
(1430 960);
DISPLAY 0.787234 (1430 960);
PAINT MONO (1430 960);
FORCEPROP 1 LAST PATH I32
J 0
(1475 1225);
DISPLAY 0.978723 (1475 1225);
PAINT WHITE (1475 1225);
DISPLAY INVISIBLE (1475 1225);
FORCEPROP 2 LAST CDS_LIB pure_quanta
J 0
(1425 1050);
DISPLAY INVISIBLE (1425 1050);
FORCEPROP 2 LAST CDS_LOCATION R4500
J 0
(1475 1275);
DISPLAY 1.021277 (1475 1275);
DISPLAY INVISIBLE (1475 1275);
FORCEPROP 2 LAST $SEC 1
J 0
(1475 1275);
DISPLAY 0.680851 (1475 1275);
PAINT MONO (1475 1275);
DISPLAY INVISIBLE (1475 1275);
FORCEPROP 2 LAST CDS_SEC 1
J 0
(1475 1275);
DISPLAY 1.021277 (1475 1275);
DISPLAY INVISIBLE (1475 1275);
FORCEADD Q_RES..1
(2200 675);
FORCEPROP 1 LAST PART_NUMBER CS03322FB03
J 0
(2150 725);
DISPLAY 0.404255 (2150 725);
DISPLAY INVISIBLE (2150 725);
FORCEPROP 1 LAST MATERIAL CHIP
J 0
(2500 675);
DISPLAY 0.510638 (2500 675);
FORCEPROP 1 LAST TOLERANCE 1%
J 0
(2425 675);
DISPLAY 0.510638 (2425 675);
FORCEPROP 1 LAST VALUE 33.2
J 2
(2400 675);
DISPLAY 0.510638 (2400 675);
FORCEPROP 1 LAST $LOCATION R4540
J 0
(1975 675);
DISPLAY 0.638298 (1975 675);
FORCEPROP 1 LASTPIN (2100 675) $PN 1
J 0
(2112 687);
DISPLAY 0.787234 (2112 687);
PAINT MONO (2112 687);
FORCEPROP 1 LASTPIN (2300 675) $PN 2
J 0
(2262 687);
DISPLAY 0.787234 (2262 687);
PAINT MONO (2262 687);
FORCEPROP 1 LAST WATTAGE 1/16W
J 2
(2375 750);
DISPLAY 0.404255 (2375 750);
DISPLAY INVISIBLE (2375 750);
FORCEPROP 1 LAST PACK_TYPE 0402LF
J 0
(2450 675);
DISPLAY 0.510638 (2450 675);
DISPLAY INVISIBLE (2450 675);
FORCEPROP 1 LAST PATH I33
J 0
(2150 825);
DISPLAY 0.978723 (2150 825);
PAINT WHITE (2150 825);
DISPLAY INVISIBLE (2150 825);
FORCEPROP 2 LAST CDS_LIB pure_quanta
J 0
(2200 675);
DISPLAY INVISIBLE (2200 675);
FORCEPROP 0 LAST CDS_LOCATION R4540
J 0
(2050 725);
DISPLAY 1.021277 (2050 725);
DISPLAY INVISIBLE (2050 725);
FORCEPROP 0 LAST $SEC 1
J 0
(2050 725);
DISPLAY 0.680851 (2050 725);
PAINT MONO (2050 725);
DISPLAY INVISIBLE (2050 725);
FORCEPROP 0 LAST CDS_SEC 1
J 0
(2050 725);
DISPLAY 1.021277 (2050 725);
DISPLAY INVISIBLE (2050 725);
FORCEADD Q_RES..1
(2200 575);
FORCEPROP 1 LAST PART_NUMBER CS03322FB03
J 0
(2075 750);
DISPLAY 0.510638 (2075 750);
DISPLAY INVISIBLE (2075 750);
FORCEPROP 1 LAST PACK_TYPE 0402LF
J 0
(2075 800);
DISPLAY 0.510638 (2075 800);
FORCEPROP 1 LAST TOLERANCE 1%
J 0
(2425 575);
DISPLAY 0.510638 (2425 575);
FORCEPROP 1 LAST MATERIAL CHIP
J 0
(2500 575);
DISPLAY 0.510638 (2500 575);
FORCEPROP 1 LAST VALUE 33.2
J 2
(2400 575);
DISPLAY 0.510638 (2400 575);
FORCEPROP 1 LAST WATTAGE 1/16W
J 2
(2375 800);
DISPLAY 0.510638 (2375 800);
FORCEPROP 1 LAST $LOCATION R4541
J 0
(1975 575);
DISPLAY 0.638298 (1975 575);
FORCEPROP 1 LASTPIN (2100 575) $PN 1
J 0
(2112 587);
DISPLAY 0.787234 (2112 587);
PAINT MONO (2112 587);
FORCEPROP 1 LASTPIN (2300 575) $PN 2
J 0
(2262 587);
DISPLAY 0.787234 (2262 587);
PAINT MONO (2262 587);
FORCEPROP 2 LAST CDS_LIB pure_quanta
J 0
(2200 575);
DISPLAY INVISIBLE (2200 575);
FORCEPROP 1 LAST PATH I34
J 0
(2150 725);
DISPLAY 0.978723 (2150 725);
PAINT WHITE (2150 725);
DISPLAY INVISIBLE (2150 725);
FORCEPROP 0 LAST CDS_LOCATION R4541
J 0
(2375 825);
DISPLAY 1.021277 (2375 825);
DISPLAY INVISIBLE (2375 825);
FORCEPROP 0 LAST $SEC 1
J 0
(2375 825);
DISPLAY 0.680851 (2375 825);
PAINT MONO (2375 825);
DISPLAY INVISIBLE (2375 825);
FORCEPROP 0 LAST CDS_SEC 1
J 0
(2375 825);
DISPLAY 1.021277 (2375 825);
DISPLAY INVISIBLE (2375 825);
FORCEADD OFFPAGE..2
(3500 675);
FORCEPROP 2 LAST $XR0 237 
J 0
(3689 675);
DISPLAY 0.638298 (3689 675);
PAINT MONO (3689 675);
FORCEPROP 2 LAST CDS_LIB standard
J 0
(3500 675);
DISPLAY INVISIBLE (3500 675);
FORCEPROP 1 LAST OFFPAGE TRUE
J 0
(3825 550);
DISPLAY 0.872340 (3825 550);
PAINT GREEN (3825 550);
DISPLAY INVISIBLE (3825 550);
FORCEPROP 1 LAST COMMENT_BODY TRUE
J 0
(3455 580);
DISPLAY 0.872340 (3455 580);
PAINT GREEN (3455 580);
DISPLAY INVISIBLE (3455 580);
FORCEPROP 2 LAST PATH I35
J 0
(3700 725);
DISPLAY 1.021277 (3700 725);
DISPLAY INVISIBLE (3700 725);
FORCEADD OFFPAGE..3
(3500 575);
FORCEPROP 2 LAST $XR0 237 
J 0
(3714 575);
DISPLAY 0.638298 (3714 575);
PAINT MONO (3714 575);
FORCEPROP 2 LAST CDS_LIB standard
J 0
(3500 575);
DISPLAY INVISIBLE (3500 575);
FORCEPROP 1 LAST OFFPAGE TRUE
J 0
(3825 450);
DISPLAY 0.872340 (3825 450);
PAINT GREEN (3825 450);
DISPLAY INVISIBLE (3825 450);
FORCEPROP 1 LAST COMMENT_BODY TRUE
J 0
(3450 475);
DISPLAY 0.872340 (3450 475);
PAINT GREEN (3450 475);
DISPLAY INVISIBLE (3450 475);
FORCEPROP 2 LAST PATH I36
J 0
(3725 625);
DISPLAY 1.021277 (3725 625);
DISPLAY INVISIBLE (3725 625);
FORCEADD UNIVERSAL_GND..1
(-950 850);
FORCEPROP 3 LASTPIN (-950 900) SIG_NAME GND\g
J 0
(-940 910);
DISPLAY 0.659574 (-940 910);
PAINT MONO (-940 910);
DISPLAY INVISIBLE (-940 910);
FORCEPROP 1 LAST PATH I4
J 0
(-875 850);
DISPLAY 0.872340 (-875 850);
PAINT AQUA (-875 850);
DISPLAY INVISIBLE (-875 850);
FORCEPROP 1 LAST HDL_POWER GND
J 1
(-925 775);
DISPLAY 0.872340 (-925 775);
PAINT GREEN (-925 775);
DISPLAY INVISIBLE (-925 775);
FORCEPROP 2 LAST CDS_LIB logical_power
J 0
(-950 850);
PAINT MONO (-950 850);
DISPLAY INVISIBLE (-950 850);
FORCEADD Q_CAP..1
(-950 1075);
FORCEPROP 1 LAST PART_NUMBER CH4104K1B00
J 0
(-900 925);
DISPLAY 0.510638 (-900 925);
DISPLAY INVISIBLE (-900 925);
FORCEPROP 1 LAST VALUE 0.1UF
J 0
(-900 1125);
DISPLAY 0.510638 (-900 1125);
FORCEPROP 1 LAST VOLTAGE 25V
J 0
(-900 1075);
DISPLAY 0.510638 (-900 1075);
FORCEPROP 1 LAST TOLERANCE 10%
J 0
(-900 1025);
DISPLAY 0.510638 (-900 1025);
FORCEPROP 1 LAST MATERIAL X7R
J 0
(-900 975);
DISPLAY 0.510638 (-900 975);
FORCEPROP 1 LAST PACK_TYPE 0402
J 0
(-900 875);
DISPLAY 0.510638 (-900 875);
FORCEPROP 1 LAST $LOCATION C2337
J 0
(-900 1175);
DISPLAY 0.978723 (-900 1175);
FORCEPROP 1 LASTPIN (-950 1175) $PN 1
J 0
(-940 1155);
DISPLAY 0.787234 (-940 1155);
FORCEPROP 1 LASTPIN (-950 975) $PN 2
J 0
(-940 955);
DISPLAY 0.787234 (-940 955);
FORCEPROP 1 LAST PATH I5
J 0
(-900 1225);
DISPLAY 0.978723 (-900 1225);
PAINT WHITE (-900 1225);
DISPLAY INVISIBLE (-900 1225);
FORCEPROP 2 LAST CDS_LIB pure_quanta
J 0
(-950 1075);
PAINT MONO (-950 1075);
DISPLAY INVISIBLE (-950 1075);
FORCEPROP 2 LAST CDS_LOCATION C2337
J 0
(-900 1275);
DISPLAY 1.021277 (-900 1275);
DISPLAY INVISIBLE (-900 1275);
FORCEPROP 2 LAST $SEC 1
J 0
(-900 1275);
DISPLAY 0.680851 (-900 1275);
PAINT MONO (-900 1275);
DISPLAY INVISIBLE (-900 1275);
FORCEPROP 2 LAST CDS_SEC 1
J 0
(-900 1275);
DISPLAY 1.021277 (-900 1275);
DISPLAY INVISIBLE (-900 1275);
FORCEADD UNIVERSAL_POWER..1
(-600 1375);
FORCEPROP 3 LASTPIN (-600 1325) SIG_NAME P3V3_AUX\g
J 0
(-590 1335);
DISPLAY 0.659574 (-590 1335);
PAINT MONO (-590 1335);
DISPLAY INVISIBLE (-590 1335);
FORCEPROP 1 LAST HDL_POWER P3V3_AUX
J 1
(-600 1425);
DISPLAY 0.872340 (-600 1425);
PAINT GREEN (-600 1425);
FORCEPROP 1 LAST PATH I6
J 0
(-550 1400);
DISPLAY 0.872340 (-550 1400);
PAINT AQUA (-550 1400);
DISPLAY INVISIBLE (-550 1400);
FORCEPROP 2 LAST CDS_LIB logical_power
J 0
(-600 1375);
PAINT MONO (-600 1375);
DISPLAY INVISIBLE (-600 1375);
FORCEADD UNIVERSAL_GND..1
(725 875);
FORCEPROP 3 LASTPIN (725 925) SIG_NAME GND\g
J 0
(735 935);
DISPLAY 0.659574 (735 935);
PAINT MONO (735 935);
DISPLAY INVISIBLE (735 935);
FORCEPROP 1 LAST PATH I7
J 0
(800 875);
DISPLAY 0.872340 (800 875);
PAINT AQUA (800 875);
DISPLAY INVISIBLE (800 875);
FORCEPROP 2 LAST CDS_LIB logical_power
J 0
(725 875);
DISPLAY INVISIBLE (725 875);
FORCEPROP 1 LAST HDL_POWER GND
J 1
(750 800);
DISPLAY 0.872340 (750 800);
PAINT GREEN (750 800);
DISPLAY INVISIBLE (750 800);
FORCEADD Q_CAP..1
(725 1075);
FORCEPROP 1 LAST PART_NUMBER CH4104K1B00
J 0
(775 925);
DISPLAY 0.510638 (775 925);
DISPLAY INVISIBLE (775 925);
FORCEPROP 1 LAST PACK_TYPE 0402
J 0
(775 875);
DISPLAY 0.510638 (775 875);
FORCEPROP 1 LAST VOLTAGE 25V
J 0
(775 1075);
DISPLAY 0.510638 (775 1075);
FORCEPROP 1 LAST VALUE 0.1UF
J 0
(775 1125);
DISPLAY 0.510638 (775 1125);
FORCEPROP 1 LAST MATERIAL X7R
J 0
(775 975);
DISPLAY 0.510638 (775 975);
FORCEPROP 1 LAST TOLERANCE 10%
J 0
(775 1025);
DISPLAY 0.510638 (775 1025);
FORCEPROP 1 LAST $LOCATION C2338
J 0
(775 1175);
DISPLAY 0.978723 (775 1175);
FORCEPROP 1 LASTPIN (725 1175) $PN 1
J 0
(735 1155);
DISPLAY 0.787234 (735 1155);
PAINT MONO (735 1155);
FORCEPROP 1 LASTPIN (725 975) $PN 2
J 0
(735 955);
DISPLAY 0.787234 (735 955);
PAINT MONO (735 955);
FORCEPROP 1 LAST PATH I8
J 0
(775 1225);
DISPLAY 0.978723 (775 1225);
PAINT WHITE (775 1225);
DISPLAY INVISIBLE (775 1225);
FORCEPROP 2 LAST CDS_LIB pure_quanta
J 0
(725 1075);
DISPLAY INVISIBLE (725 1075);
FORCEPROP 0 LAST CDS_LOCATION C2338
J 0
(775 1225);
DISPLAY 1.021277 (775 1225);
DISPLAY INVISIBLE (775 1225);
FORCEPROP 0 LAST $SEC 1
J 0
(775 1225);
DISPLAY 0.680851 (775 1225);
PAINT MONO (775 1225);
DISPLAY INVISIBLE (775 1225);
FORCEPROP 0 LAST CDS_SEC 1
J 0
(775 1225);
DISPLAY 1.021277 (775 1225);
DISPLAY INVISIBLE (775 1225);
FORCEADD UNIVERSAL_POWER..1
(525 1375);
FORCEPROP 3 LASTPIN (525 1325) SIG_NAME P3V3\g
J 0
(535 1335);
DISPLAY 0.659574 (535 1335);
PAINT MONO (535 1335);
DISPLAY INVISIBLE (535 1335);
FORCEPROP 1 LAST HDL_POWER P3V3
J 1
(525 1425);
DISPLAY 0.872340 (525 1425);
PAINT GREEN (525 1425);
FORCEPROP 1 LAST PATH I9
J 0
(575 1400);
DISPLAY 0.872340 (575 1400);
PAINT AQUA (575 1400);
DISPLAY INVISIBLE (575 1400);
FORCEPROP 2 LAST CDS_LIB logical_power
J 0
(525 1375);
DISPLAY INVISIBLE (525 1375);
FORCEADD QUANTA_TITLE_BLOCK_C..1
(5475 -4325);
FORCEPROP 0 LAST CDS_CON_LAST_MODIFIED Fri Aug 25 14:04:01 2023
J 0
(3590 -4310);
DISPLAY INVISIBLE (3590 -4310);
FORCEPROP 1 LAST CUSTOM_TXT_CDS <CON_LAST_MODIFIED>
J 0
(3590 -4310);
DISPLAY 0.978723 (3590 -4310);
FORCEPROP 2 LAST CUSTOM_TXT_CDS <XR_PAGE_TITLE>
J 0
(-2415 925);
DISPLAY 0.638298 (-2415 925);
PAINT PINK (-2415 925);
DISPLAY INVISIBLE (-2415 925);
FORCEPROP 1 LAST CUSTOM_TXT_CDS <NAME_2>
J 0
(2300 -4275);
FORCEPROP 1 LAST CUSTOM_TXT_CDS <NAME_1>
J 0
(2300 -4150);
FORCEPROP 1 LAST CUSTOM_TXT_CDS <Q_NUMBER>
J 0
(4072 -4222);
DISPLAY 1.212766 (4072 -4222);
FORCEPROP 1 LAST CUSTOM_TXT_CDS <Q_PROJ>
J 0
(3093 -4223);
DISPLAY 1.212766 (3093 -4223);
FORCEPROP 1 LAST CUSTOM_TXT_CDS <Q_REV>
J 0
(5291 -4222);
DISPLAY 1.212766 (5291 -4222);
FORCEPROP 1 LAST CUSTOM_TXT_CDS <CON_PAGE_NUM> OF <CON_TOTAL_PAGES>
J 0
(5029 -4307);
DISPLAY 0.978723 (5029 -4307);
FORCEPROP 1 LAST Q_TITLE SMBUS - ISOLATED
J 0
(-3891 -4299);
DISPLAY 2.446809 (-3891 -4299);
PAINT GREEN (-3891 -4299);
FORCEPROP 1 LAST Q_DEPT 
J 1
(1712 -4276);
DISPLAY 1.957447 (1712 -4276);
PAINT GREEN (1712 -4276);
FORCEPROP 2 LAST CDS_XR_PAGE_TITLE CR-237 : @S9S_MB_2U_LIB.S9S_MB_2U(SCH_1):PAGE237
J 0
(-2415 925);
DISPLAY 0.638298 (-2415 925);
PAINT PINK (-2415 925);
DISPLAY INVISIBLE (-2415 925);
FORCEPROP 2 LAST PAGE_BORDER TRUE
J 0
(-2415 925);
DISPLAY 0.638298 (-2415 925);
PAINT PINK (-2415 925);
DISPLAY INVISIBLE (-2415 925);
FORCEPROP 1 LAST COMMENT_BODY TRUE
J 0
(5487 -4338);
DISPLAY 0.978723 (5487 -4338);
PAINT GREEN (5487 -4338);
DISPLAY INVISIBLE (5487 -4338);
FORCEPROP 1 LAST CDS_LMAN_SYM_OUTLINE -9475,6775,100,-125
J 0
(5475 -4325);
DISPLAY 0.468085 (5475 -4325);
PAINT GREEN (5475 -4325);
DISPLAY INVISIBLE (5475 -4325);
FORCEPROP 2 LAST CDS_LIB pure_quanta
J 0
(5475 -4325);
DISPLAY INVISIBLE (5475 -4325);
WIRE 16 -1 (525 1325)(525 1250);
WIRE 16 -1 (-600 1250)(-600 1325);
WIRE 16 -1 (-600 1250)(-950 1250);
WIRE 16 -1 (-600 1250)(-600 825);
WIRE 16 -1 (1425 1250)(1425 1275);
WIRE 16 -1 (1425 1250)(1700 1250);
WIRE 16 -1 (1425 1250)(1425 1150);
WIRE 16 -1 (725 975)(725 925);
WIRE 16 -1 (-950 975)(-950 900);
WIRE 16 -1 (-550 250)(-550 425);
WIRE 16 -1 (400 575)(1950 575);
FORCEPROP 0 LAST CDS_PHYS_NET_NAME SMB_OCP_SFF_3V3AUX_BUF_SDA
J 0
(440 623);
PAINT MONO (440 623);
DISPLAY INVISIBLE (440 623);
FORCEPROP 2 LAST SIG_NAME SMB_HOST_CLK_BUF_ISO_3V3AUX_SDA_R
J 0
(540 585);
DISPLAY 0.510638 (540 585);
PAINT WHITE (540 585);
WIRE 16 -1 (2100 575)(1950 575);
WIRE 16 -1 (1950 925)(1950 575);
WIRE 16 -1 (725 1250)(725 1175);
WIRE 16 -1 (525 825)(400 825);
WIRE 16 -1 (525 1250)(525 825);
WIRE 16 -1 (525 1250)(725 1250);
WIRE 16 -1 (1700 1125)(1700 1250);
WIRE 16 -1 (1700 1250)(1950 1250);
WIRE 16 -1 (1950 1125)(1950 1250);
WIRE 16 -1 (1700 925)(1700 675);
WIRE 16 -1 (1700 675)(2100 675);
WIRE 16 -1 (400 675)(1700 675);
FORCEPROP 0 LAST CDS_PHYS_NET_NAME SMB_OCP_SFF_3V3AUX_BUF_SCL
J 0
(440 723);
PAINT MONO (440 723);
DISPLAY INVISIBLE (440 723);
FORCEPROP 2 LAST SIG_NAME SMB_HOST_CLK_BUF_ISO_3V3AUX_SCL_R
J 0
(540 685);
DISPLAY 0.510638 (540 685);
PAINT WHITE (540 685);
WIRE 16 -1 (400 425)(1425 425);
FORCEPROP 0 LAST CDS_PHYS_NET_NAME HP_LVC3_OCP_V3_1_R_EN
J 0
(1065 467);
PAINT MONO (1065 467);
DISPLAY INVISIBLE (1065 467);
FORCEPROP 2 LAST SIG_NAME PU_CLK_BUF_ISO_EN
J 0
(540 435);
DISPLAY 0.553191 (540 435);
PAINT WHITE (540 435);
FORCEPROP 0 LAST $PHYS_NET_NAME RST_PCIE_M2_N
J 0
(1065 514);
PAINT MONO (1065 514);
DISPLAY INVISIBLE (1065 514);
WIRE 16 -1 (1425 950)(1425 425);
WIRE 16 -1 (2300 575)(3450 575);
FORCEPROP 0 LAST CDS_PHYS_NET_NAME SMB_OCP_SFF_3V3AUX_BUF_SDA
J 0
(2340 623);
PAINT MONO (2340 623);
DISPLAY INVISIBLE (2340 623);
FORCEPROP 2 LAST SIG_NAME SMB_HOST_CLK_BUF_ISO_3V3AUX_SDA
J 0
(2665 585);
DISPLAY 0.510638 (2665 585);
PAINT WHITE (2665 585);
WIRE 16 -1 (2300 675)(3450 675);
FORCEPROP 0 LAST CDS_PHYS_NET_NAME SMB_OCP_SFF_3V3AUX_BUF_SCL
J 0
(2340 723);
PAINT MONO (2340 723);
DISPLAY INVISIBLE (2340 723);
FORCEPROP 2 LAST SIG_NAME SMB_HOST_CLK_BUF_ISO_3V3AUX_SCL
J 0
(2665 685);
DISPLAY 0.510638 (2665 685);
PAINT WHITE (2665 685);
WIRE 16 -1 (3175 -1025)(1650 -1025);
FORCEPROP 2 LAST SIG_NAME SMB_HOST_DB2000_3V3AUX_SDA
J 0
(2140 -1015);
DISPLAY 0.702128 (2140 -1015);
PAINT WHITE (2140 -1015);
WIRE 16 -1 (-450 575)(-1975 575);
FORCEPROP 2 LAST SIG_NAME SMB_HOST_CLK_BUF_3V3AUX_SDA
J 0
(-1485 585);
DISPLAY 0.702128 (-1485 585);
PAINT WHITE (-1485 585);
WIRE 16 -1 (-450 675)(-1975 675);
FORCEPROP 2 LAST SIG_NAME SMB_HOST_CLK_BUF_3V3AUX_SCL
J 0
(-1485 685);
DISPLAY 0.702128 (-1485 685);
PAINT WHITE (-1485 685);
WIRE 16 -1 (-600 825)(-450 825);
WIRE 16 -1 (-950 1175)(-950 1250);
WIRE 16 -1 (975 -1525)(1425 -1525);
WIRE 16 -1 (975 -975)(975 -1525);
WIRE 16 -1 (1450 -975)(975 -975);
WIRE 16 -1 (-1250 -975)(975 -975);
FORCEPROP 0 LAST CDS_PHYS_NET_NAME SMB_OCP_SFF_3V3AUX_BUF_SCL
J 0
(-1210 -927);
PAINT MONO (-1210 -927);
DISPLAY INVISIBLE (-1210 -927);
FORCEPROP 2 LAST SIG_NAME SMB_HOST_CLK_BUF_ISO_3V3AUX_SCL
J 0
(-1110 -965);
DISPLAY 0.510638 (-1110 -965);
PAINT WHITE (-1110 -965);
WIRE 16 -1 (850 -1025)(-1250 -1025);
FORCEPROP 0 LAST CDS_PHYS_NET_NAME SMB_OCP_SFF_3V3AUX_BUF_SDA
J 0
(-1210 -977);
PAINT MONO (-1210 -977);
DISPLAY INVISIBLE (-1210 -977);
FORCEPROP 2 LAST SIG_NAME SMB_HOST_CLK_BUF_ISO_3V3AUX_SDA
J 0
(-1110 -1015);
DISPLAY 0.510638 (-1110 -1015);
PAINT WHITE (-1110 -1015);
WIRE 16 -1 (1450 -1025)(850 -1025);
WIRE 16 -1 (850 -1025)(850 -1575);
WIRE 16 -1 (1425 -1575)(850 -1575);
WIRE 16 -1 (3150 -1525)(1625 -1525);
FORCEPROP 2 LAST SIG_NAME SMB_HOST_9ZXL045_3V3AUX_SCL
J 0
(2115 -1515);
DISPLAY 0.702128 (2115 -1515);
PAINT WHITE (2115 -1515);
WIRE 16 -1 (3175 -975)(1650 -975);
FORCEPROP 2 LAST SIG_NAME SMB_HOST_DB2000_3V3AUX_SCL
J 0
(2140 -965);
DISPLAY 0.702128 (2140 -965);
PAINT WHITE (2140 -965);
WIRE 16 -1 (3150 -1575)(1625 -1575);
FORCEPROP 2 LAST SIG_NAME SMB_HOST_9ZXL045_3V3AUX_SDA
J 0
(2115 -1565);
DISPLAY 0.702128 (2115 -1565);
PAINT WHITE (2115 -1565);
WIRE 16 -1 (-550 425)(-450 425);
DOT 1 (1700 1250);
DOT 1 (850 -1025);
DOT 1 (975 -975);
DOT 1 (525 1250);
DOT 1 (-600 1250);
DOT 1 (1425 1250);
DOT 1 (1700 675);
DOT 1 (1950 575);
FORCENOTE
20210904 MODIFY FOR GT
(-3625 2100) 0;
DISPLAY LEFT (-3625 2100);
DISPLAY 2.510638 (-3625 2100);
PAINT PINK (-3625 2100);
QUIT
